# S9S_MB_2U (Grand Teton) — schematic netlist excerpt (pin names and nets, part order shuffled) for the footprints in the layout excerpt that follows; sources: Cadence DE-HDL packaged netlist, KiCad conversion of 03242023_DA0F0TMBIJ0_F0T_Motherboard_J_brd_V01_OCP.brd

C1836  Q_CAP  0.1UF 25V 10% X7R  pkg 0402  page 159 : A = P3V3_OCP_V3_2 ; B = GND
R3655  Q_RES  0 5% CHIP  pkg 0402LF  page 152 : A = P3V3_AUX ; B = P3V3_AUX_USB_HUB

(kicad_pcb
	(version 20260206)
	(generator "pcbnew")
	(generator_version "10.0")
	(general
		(thickness 1.6)
		(legacy_teardrops no)
	)
	(paper "A4")
	(title_block
		(title "03242023_DA0F0TMBIJ0_F0T_Motherboard_J_brd_V01_OCP.brd")
		(comment 1 "Grand Teton / footprints 4331-4332 of 6105")
	)
	(layers
		(0 "F.Cu" signal "TOP")
		(4 "In1.Cu" signal "GND")
		(6 "In2.Cu" signal "IN1")
		(8 "In3.Cu" signal "GND1")
		(10 "In4.Cu" signal "IN2")
		(12 "In5.Cu" signal "GND2")
		(14 "In6.Cu" signal "IN3")
		(16 "In7.Cu" signal "GND3")
		(18 "In8.Cu" signal "VCC")
		(20 "In9.Cu" signal "VCC1")
		(22 "In10.Cu" signal "GND4")
		(24 "In11.Cu" signal "IN4")
		(26 "In12.Cu" signal "GND5")
		(28 "In13.Cu" signal "IN5")
		(30 "In14.Cu" signal "GND6")
		(32 "In15.Cu" signal "IN6")
		(34 "In16.Cu" signal "GND7")
		(2 "B.Cu" signal "BOTTOM")
		(9 "F.Adhes" user "F.Adhesive")
		(11 "B.Adhes" user "B.Adhesive")
		(13 "F.Paste" user "Package Geometry/Pastemask Top")
		(15 "B.Paste" user "Package Geometry/Pastemask Bottom")
		(5 "F.SilkS" user "Ref Des/Silkscreen Top")
		(7 "B.SilkS" user "Ref Des/Silkscreen Bottom")
		(1 "F.Mask" user "Board Geometry/Soldermask Top")
		(3 "B.Mask" user "Board Geometry/Soldermask Bottom")
		(17 "Dwgs.User" user "User.Drawings")
		(19 "Cmts.User" user "User.Comments")
		(21 "Eco1.User" user "User.Eco1")
		(23 "Eco2.User" user "User.Eco2")
		(25 "Edge.Cuts" user "Board Geometry/Outline")
		(27 "Margin" user)
		(31 "F.CrtYd" user "Package Geometry/Place Bound Top")
		(29 "B.CrtYd" user "Package Geometry/Place Bound Bottom")
		(35 "F.Fab" user "Ref Des/Assembly Top")
		(33 "B.Fab" user "Ref Des/Assembly Bottom")
	)
	(footprint ""
		(layer "B.Cu")
		(at 18.838926 -97.330768 -90)
		(property "Reference" "R3655"
			(at 0 0 90)
			(layer "B.SilkS")
			(hide yes)
			(effects
				(font
					(size 1.27 1.27)
				)
				(justify mirror)
			)
		)
		(property "Value" ""
			(at 0 0 90)
			(layer "B.Fab")
			(effects
				(font
					(size 1.27 1.27)
				)
				(justify mirror)
			)
		)
		(duplicate_pad_numbers_are_jumpers no)
		(fp_line
			(start -0.7874 0.4064)
			(end 0.7874 0.4064)
			(stroke
				(width 0.1524)
				(type default)
			)
			(layer "B.SilkS")
		)
		(fp_line
			(start 0.7874 0.4064)
			(end 0.7874 -0.4064)
			(stroke
				(width 0.1524)
				(type default)
			)
			(layer "B.SilkS")
		)
		(fp_line
			(start -0.7874 -0.4064)
			(end -0.7874 0.4064)
			(stroke
				(width 0.1524)
				(type default)
			)
			(layer "B.SilkS")
		)
		(fp_line
			(start 0.7874 -0.4064)
			(end -0.7874 -0.4064)
			(stroke
				(width 0.1524)
				(type default)
			)
			(layer "B.SilkS")
		)
		(fp_line
			(start -0.67945 0.3048)
			(end -0.120396 0.3048)
			(stroke
				(width 0.1)
				(type default)
			)
			(layer "B.Fab")
		)
		(fp_line
			(start -0.120396 0.3048)
			(end -0.120396 0.2794)
			(stroke
				(width 0.1)
				(type default)
			)
			(layer "B.Fab")
		)
		(fp_line
			(start 0.12065 0.3048)
			(end 0.67945 0.3048)
			(stroke
				(width 0.1)
				(type default)
			)
			(layer "B.Fab")
		)
		(fp_line
			(start 0.67945 0.3048)
			(end 0.67945 -0.305054)
			(stroke
				(width 0.1)
				(type default)
			)
			(layer "B.Fab")
		)
		(fp_line
			(start -0.120396 0.2794)
			(end 0.12065 0.2794)
			(stroke
				(width 0.1)
				(type default)
			)
			(layer "B.Fab")
		)
		(fp_line
			(start 0.12065 0.2794)
			(end 0.12065 0.3048)
			(stroke
				(width 0.1)
				(type default)
			)
			(layer "B.Fab")
		)
		(fp_line
			(start -0.12065 -0.2794)
			(end -0.12065 -0.3048)
			(stroke
				(width 0.1)
				(type default)
			)
			(layer "B.Fab")
		)
		(fp_line
			(start 0.12065 -0.2794)
			(end -0.12065 -0.2794)
			(stroke
				(width 0.1)
				(type default)
			)
			(layer "B.Fab")
		)
		(fp_line
			(start -0.67945 -0.3048)
			(end -0.67945 0.3048)
			(stroke
				(width 0.1)
				(type default)
			)
			(layer "B.Fab")
		)
		(fp_line
			(start -0.12065 -0.3048)
			(end -0.67945 -0.3048)
			(stroke
				(width 0.1)
				(type default)
			)
			(layer "B.Fab")
		)
		(fp_line
			(start 0.12065 -0.305054)
			(end 0.12065 -0.2794)
			(stroke
				(width 0.1)
				(type default)
			)
			(layer "B.Fab")
		)
		(fp_line
			(start 0.67945 -0.305054)
			(end 0.12065 -0.305054)
			(stroke
				(width 0.1)
				(type default)
			)
			(layer "B.Fab")
		)
		(pad "1" smd circle
			(at 0.40005 0 90)
			(size 0 0)
			(layers "B.Cu" "B.Mask" "B.Paste")
			(net "P3V3_AUX")
		)
		(pad "2" smd circle
			(at -0.40005 0 90)
			(size 0 0)
			(layers "B.Cu" "B.Mask" "B.Paste")
			(net "P3V3_AUX_USB_HUB")
		)
	)
	(footprint ""
		(layer "B.Cu")
		(at 61.52388 -8.981948 90)
		(property "Reference" "C1836"
			(at 0 0 90)
			(layer "B.SilkS")
			(hide yes)
			(effects
				(font
					(size 1.27 1.27)
				)
				(justify mirror)
			)
		)
		(property "Value" ""
			(at 0 0 90)
			(layer "B.Fab")
			(effects
				(font
					(size 1.27 1.27)
				)
				(justify mirror)
			)
		)
		(duplicate_pad_numbers_are_jumpers no)
		(fp_line
			(start 0.7874 -0.4064)
			(end -0.7874 -0.4064)
			(stroke
				(width 0.1524)
				(type default)
			)
			(layer "B.SilkS")
		)
		(fp_line
			(start -0.7874 -0.4064)
			(end -0.7874 0.4064)
			(stroke
				(width 0.1524)
				(type default)
			)
			(layer "B.SilkS")
		)
		(fp_line
			(start 0.7874 0.4064)
			(end 0.7874 -0.4064)
			(stroke
				(width 0.1524)
				(type default)
			)
			(layer "B.SilkS")
		)
		(fp_line
			(start -0.7874 0.4064)
			(end 0.7874 0.4064)
			(stroke
				(width 0.1524)
				(type default)
			)
			(layer "B.SilkS")
		)
		(fp_line
			(start 0.67945 -0.305054)
			(end 0.12065 -0.305054)
			(stroke
				(width 0.1)
				(type default)
			)
			(layer "B.Fab")
		)
		(fp_line
			(start 0.12065 -0.305054)
			(end 0.12065 -0.2794)
			(stroke
				(width 0.1)
				(type default)
			)
			(layer "B.Fab")
		)
		(fp_line
			(start -0.12065 -0.3048)
			(end -0.67945 -0.3048)
			(stroke
				(width 0.1)
				(type default)
			)
			(layer "B.Fab")
		)
		(fp_line
			(start -0.67945 -0.3048)
			(end -0.67945 0.3048)
			(stroke
				(width 0.1)
				(type default)
			)
			(layer "B.Fab")
		)
		(fp_line
			(start 0.12065 -0.2794)
			(end -0.12065 -0.2794)
			(stroke
				(width 0.1)
				(type default)
			)
			(layer "B.Fab")
		)
		(fp_line
			(start -0.12065 -0.2794)
			(end -0.12065 -0.3048)
			(stroke
				(width 0.1)
				(type default)
			)
			(layer "B.Fab")
		)
		(fp_line
			(start 0.12065 0.2794)
			(end 0.12065 0.3048)
			(stroke
				(width 0.1)
				(type default)
			)
			(layer "B.Fab")
		)
		(fp_line
			(start -0.120396 0.2794)
			(end 0.12065 0.2794)
			(stroke
				(width 0.1)
				(type default)
			)
			(layer "B.Fab")
		)
		(fp_line
			(start 0.67945 0.3048)
			(end 0.67945 -0.305054)
			(stroke
				(width 0.1)
				(type default)
			)
			(layer "B.Fab")
		)
		(fp_line
			(start 0.12065 0.3048)
			(end 0.67945 0.3048)
			(stroke
				(width 0.1)
				(type default)
			)
			(layer "B.Fab")
		)
		(fp_line
			(start -0.120396 0.3048)
			(end -0.120396 0.2794)
			(stroke
				(width 0.1)
				(type default)
			)
			(layer "B.Fab")
		)
		(fp_line
			(start -0.67945 0.3048)
			(end -0.120396 0.3048)
			(stroke
				(width 0.1)
				(type default)
			)
			(layer "B.Fab")
		)
		(pad "1" smd circle
			(at 0.40005 0 270)
			(size 0 0)
			(layers "B.Cu" "B.Mask" "B.Paste")
			(net "P3V3_OCP_V3_2")
		)
		(pad "2" smd circle
			(at -0.40005 0 270)
			(size 0 0)
			(layers "B.Cu" "B.Mask" "B.Paste")
			(net "GND")
		)
	)
)
